FILE_TYPE = CONNECTIVITY;
{Allegro Design Entry HDL 16.6-p007 (v16-6-112F) 10/10/2012}
"PAGE_NUMBER" = 238;
0"NC";
1"GND\g";
2"GND\g";
3"GND\g";
4"P3V3_STBY\g";
5"GND\g";
6"GND\g";
7"GND\g";
8"P3V3_STBY\g";
9"P1V15_AUX_BMC\g"VOLTAGE"1.5";
10"P3V3_STBY\g"VOLTAGE"3.3 V";
11"GND\g";
12"GND\g";
13"VR_P1V15_BMC_STBY_FB";
14"PWRGD_P1V15_BMC_STBY_R";
15"PWRGD_P1V2_BMC_STBY";
16"PWRGD_P1V15_BMC_STBY";
%"GND"
"1","(1025,1850)","0","mstr_symbols","I13";
;
P1V5_STBY_IBMC""
P1V5_STBY_IBMC_VR""
BOM_COST"P1V26_BMC_STBY_VR"
SIZE"1B"
CDS_LIB"mstr_symbols"
VOLTAGE"0.0V"
ROOM"P1V26_BMC_STBY_VR"
BODY_TYPE"PLUMBING"
HDL_POWER"GND";
"A\NAC"1;
%"RES"
"1","(1025,2100)","1","mstr_discrete","I14";
;
CDS_SEC"1"
WATTAGE"1/16W"
LOCATION"R9F8"
MATERIAL"CHIP"
PART_NUMBER"G21796-016"
P1V5_STBY_IBMC""
P1V5_STBY_IBMC_VR""
VALUE"10.0K"
TOLERANCE"1%"
PACK_TYPE"0402"
SEC"1"
BOM_COST"P1V26_BMC_STBY_VR"
SEC_TYPE"0402"
CDS_LIB"mstr_discrete"
CDS_LOCATION"R9F8"
ROOM"P1V26_BMC_STBY_VR";
"B"
$PN"2"13;
"A"
$PN"1"1;
%"GND"
"1","(400,2200)","0","mstr_symbols","I15";
;
P1V5_STBY_IBMC""
P1V5_STBY_IBMC_VR""
BOM_COST"P1V26_BMC_STBY_VR"
VOLTAGE"0.0V"
CDS_LIB"mstr_symbols"
SIZE"1B"
ROOM"P1V26_BMC_STBY_VR"
BODY_TYPE"PLUMBING"
HDL_POWER"GND";
"A\NAC"2;
%"CAP"
"1","(1250,3050)","0","mstr_discrete","I19";
;
VOLTAGE"50V"
TOLERANCE"10%"
MATERIAL"X7R"
VALUE"1000PF"
LOCATION"C9F8"
PART_NUMBER"A36096-046"
PACK_TYPE"0402LF"
BOM_COST"P1V26_BMC_STBY_VR"
CDS_SEC"1"
$SEC"1"
CDS_LOCATION"C9F8"
ROOM"P1V26_BMC_STBY_VR"
CDS_LIB"mstr_discrete";
"A"
$PN"1"14;
"B"
$PN"2"3;
%"GND"
"1","(1250,2825)","0","mstr_symbols","I20";
;
SIZE"1B"
CDS_LIB"mstr_symbols"
VOLTAGE"0.0V"
BOM_COST"P1V26_BMC_STBY_VR"
ROOM"P1V26_BMC_STBY_VR"
BODY_TYPE"PLUMBING"
HDL_POWER"GND";
"A\NAC"3;
%"RES"
"2","(900,3500)","0","mstr_discrete","I21";
;
CDS_SEC"1"
PACK_TYPE"0402"
PART_NUMBER"G21796-016"
MATERIAL"CHIP"
WATTAGE"1/16W"
TOLERANCE"1%"
VALUE"10.0K"
LOCATION"R9F13"
P1V5_STBY_IBMC""
P1V5_STBY_IBMC_VR""
CDS_LOCATION"R9F13"
SEC"1"
SEC_TYPE"0402"
BOM_COST"P1V26_BMC_STBY_VR"
ROOM"P1V26_BMC_STBY_VR"
CDS_LIB"mstr_discrete";
"A"
$PN"1"4;
"B"
$PN"2"14;
%"P3V3_STBY"
"1","(900,3825)","0","mstr_symbols","I22";
;
SIZE"1B"
VOLTAGE"3.3V"
CDS_LIB"mstr_symbols"
BODY_TYPE"PLUMBING"
HDL_POWER"P3V3_STBY";
"G\NAC"4;
%"CAP"
"1","(1600,2525)","0","mstr_discrete","I23";
;
CDS_SEC"1"
LOCATION"C9E10"
PACK_TYPE"0603"
MATERIAL"X6S"
VALUE"10UF"
PART_NUMBER"E15431-002"
VOLTAGE"6.3V"
TOLERANCE"20%"
CDS_LIB"mstr_discrete"
CDS_LOCATION"C9E10"
BOM_COST"P1V26_BMC_STBY_VR"
SEC"1"
ROOM"P1V26_BMC_STBY_VR"
SEC_TYPE"0603";
"A"
$PN"1"9;
"B"
$PN"2"5;
%"GND"
"1","(2325,2175)","0","mstr_symbols","I27";
;
P1V5_STBY_IBMC_VR""
P1V5_STBY_IBMC""
HDL_POWER"GND"
BODY_TYPE"PLUMBING"
ROOM"P1V26_BMC_STBY_VR"
VOLTAGE"0.0V"
SIZE"1B"
CDS_LIB"mstr_symbols"
BOM_COST"P1V26_BMC_STBY_VR";
"A\NAC"5;
%"GND"
"1","(-2000,1775)","0","mstr_symbols","I3";
;
P1V5_STBY_IBMC_VR""
P1V5_STBY_IBMC""
BOM_COST"P1V26_BMC_STBY_VR"
CDS_LIB"mstr_symbols"
SIZE"1B"
VOLTAGE"0.0V"
ROOM"P1V26_BMC_STBY_VR"
BODY_TYPE"PLUMBING"
HDL_POWER"GND";
"A\NAC"6;
%"CAP"
"1","(2325,2525)","0","mstr_discrete","I30";
;
CDS_SEC"1"
PART_NUMBER"C95333-002"
PACK_TYPE"0805LF"
VOLTAGE"4V"
VALUE"22UF"
LOCATION"C9F4"
MATERIAL"X6S"
TOLERANCE"20%"
ROOM"P1V26_BMC_STBY_VR"
CDS_LOCATION"C9F4"
SEC"1"
SEC_TYPE"0805LF"
BOM_COST"P1V26_BMC_STBY_VR"
CDS_LIB"mstr_discrete";
"A"
$PN"1"9;
"B"
$PN"2"5;
%"CAP"
"1","(-1275,2150)","0","mstr_discrete","I39";
;
CDS_SEC"1"
TOLERANCE"10%"
MATERIAL"X6S"
PART_NUMBER"D97712-011"
PACK_TYPE"0402"
VOLTAGE"16V"
LOCATION"C9E11"
VALUE"1.0UF"
SEC_TYPE"0402"
SEC"1"
CDS_LIB"mstr_discrete"
CDS_LOCATION"C9E11";
"A"
$PN"1"8;
"B"
$PN"2"7;
%"GND"
"1","(-1275,1750)","0","mstr_symbols","I4";
;
VOLTAGE"0.0V"
CDS_LIB"mstr_symbols"
SIZE"1B"
BODY_TYPE"PLUMBING"
HDL_POWER"GND";
"A\NAC"7;
%"RT9059"
"1","(-175,2700)","0","mstr_vreg","I40";
;
CDS_SEC"1"
MATERIAL"IC"
LOCATION"EU9F1"
PART_NUMBER"H65765-001"
PACK_TYPE"DFN"
SEC_TYPE"DFN"
SEC"1"
CDS_LOCATION"EU9F1"
ROOM"P1V26_BMC_STBY_VR"
CDS_LIB"mstr_vreg";
"VIN<0>"
$PN"7"10;
"VIN<1>"
$PN"8"10;
"VIN<2>"
$PN"9"10;
"EN"
$PN"6"15;
"VOUT<0>"
$PN"1"9;
"VOUT<1>"
$PN"2"9;
"VOUT<2>"
$PN"3"9;
"GND"
$PN"11"2;
"ADJ_NC"
$PN"4"13;
"VDD"
$PN"10"8;
"PGOOD"
$PN"5"14;
%"RES"
"1","(1850,3200)","0","mstr_discrete","I41";
;
CDS_SEC"1"
WATTAGE"1/16W"
VALUE"22.1"
TOLERANCE"1.0%"
LOCATION"R9F11"
PART_NUMBER"G21796-250"
MATERIAL"CHIP"
PACK_TYPE"0402"
ROOM"P1V26_BMC_STBY_VR"
SEC"1"
SEC_TYPE"0402"
CDS_LOCATION"R9F11"
CDS_LIB"mstr_discrete";
"B"
$PN"2"16;
"A"
$PN"1"14;
%"P3V3_STBY"
"1","(-1275,3075)","0","mstr_symbols","I42";
;
SIZE"1B"
CDS_LIB"mstr_symbols"
VOLTAGE"3.3V"
BODY_TYPE"PLUMBING"
HDL_POWER"P3V3_STBY";
"G\NAC"8;
%"W_VCC_CIRCLE"
"1","(2325,2825)","0","w_power","I43";
;
HDL_POWER"P1V15_AUX_BMC"
CDS_LMAN_SYM_OUTLINE"-100,100,100,-100"
CDS_LIB"w_power"
BODY_TYPE"PLUMBING";
"VCC_CIRCLE \B"9;
%"P3V3_STBY"
"1","(-2500,3550)","0","mstr_symbols","I44";
;
HDL_POWER"P3V3_STBY"
BODY_TYPE"PLUMBING"
SIZE"1B"
VOLTAGE"3.3V"
CDS_LIB"mstr_symbols";
"G\NAC"10;
%"4K42R2F-GP"
"1","(1025,2475)","0","w_hdl","I45";
;
CDS_SEC"1"
$SEC"1"
CDS_LOCATION"R9F6"
TOLERANCE"1%"
PACK_SIZE"0402"
RATED"1/16W"
LOCATION"R9F6"
VALUE"4K42R2F-GP"
ATTRIBUTE"4.42KOHM"
PACK_TYPE"SMD-RG"
PART_NUMBER"64.44215.6DL"
CDS_LIB"w_hdl"
CDS_LMAN_SYM_OUTLINE"-50,75,50,-75";
"2"
$PN"2"13;
"1"
$PN"1"9;
%"CAP"
"1","(-2050,3050)","0","mstr_discrete","I46";
;
CDS_SEC"1"
PACK_TYPE"0603"
PART_NUMBER"E15431-002"
MATERIAL"X6S"
VALUE"10UF"
POP"NOPOP"
TOLERANCE"20%"
VOLTAGE"6.3V"
LOCATION"C9W14"
SEC"1"
SEC_TYPE"0603"
ROOM"P1V26_BMC_STBY_VR"
BOM_COST"P1V26_BMC_STBY_VR"
CDS_LIB"mstr_discrete"
CDS_LOCATION"C9W14";
"A"
$PN"1"10;
"B"
$PN"2"11;
%"GND"
"1","(-2050,2775)","0","mstr_symbols","I47";
;
CDS_LIB"mstr_symbols"
SIZE"1B"
VOLTAGE"0.0V"
BODY_TYPE"PLUMBING"
HDL_POWER"GND";
"A\NAC"11;
%"CAP"
"1","(-2000,2175)","2","mstr_discrete","I5";
;
PART_NUMBER"A36096-046"
MATERIAL"EMPTY"
PACK_TYPE"0402LF"
VALUE"1000PF"
TOLERANCE"10%"
LOCATION"C9F9"
VOLTAGE"50V"
CDS_SEC"1"
$SEC"1"
CDS_LIB"mstr_discrete"
BOM_COST"P1V26_BMC_STBY_VR"
ROOM"P1V26_BMC_STBY_VR"
CDS_LOCATION"C9F9";
"A"
$PN"1"15;
"B"
$PN"2"6;
%"CAP_A"
"1","(1950,2550)","0","dev_discrete","I50";
;
VOLTAGE"4V"
VALUE"22.0UF"
LOCATION"C9W16"
TOLERANCE"20%"
MATERIAL"X6S"
PACK_TYPE"0603V"
PART_NUMBER"E15431-004"
POP"NOPOP"
ROOM"PVCCIN_CPU0_DECAP_VR"
$SEC"1"
CDS_SEC"1"
CDS_LIB"dev_discrete"
BOM_COST"PROC_SOCKET"
CDS_LOCATION"C9W16";
"B"
$PN"2"5;
"A"
$PN"1"9;
%"GND"
"1","(-2500,2775)","0","mstr_symbols","I6";
;
HDL_POWER"GND"
BODY_TYPE"PLUMBING"
VOLTAGE"0.0V"
SIZE"1B"
CDS_LIB"mstr_symbols";
"A\NAC"12;
%"CAP"
"1","(-2500,3025)","0","mstr_discrete","I7";
;
CDS_SEC"1"
MATERIAL"X6S"
TOLERANCE"20%"
VOLTAGE"6.3V"
VALUE"10UF"
LOCATION"C9F3"
PACK_TYPE"0603"
PART_NUMBER"E15431-002"
CDS_LIB"mstr_discrete"
BOM_COST"P1V26_BMC_STBY_VR"
CDS_LOCATION"C9F3"
ROOM"P1V26_BMC_STBY_VR"
SEC_TYPE"0603"
SEC"1";
"A"
$PN"1"10;
"B"
$PN"2"12;
END.
